# S9S_MB_2U (Grand Teton) — schematic netlist excerpt (pin names and nets, part order shuffled) for the footprints in the layout excerpt that follows; sources: Cadence DE-HDL packaged netlist, KiCad conversion of 03242023_DA0F0TMBIJ0_F0T_Motherboard_J_brd_V01_OCP.brd

PU294  MAX15090BEWIT  MAX15090BEWI+T EMPTY  pkg BGA28_0-5_3-525X2-065  page 192
  ISENSE  = P12V_E1S_SENSE_0
  VCC  = P12V_E1S_VCC_0
  IN_A3  = P12V_AUX
  OUT_A4  = P12V_E1S_0
  IN_A5  = P12V_AUX
  GATE  = P12V_E1S_GATE_0
  CDLY  = GND
  CB  = P12V_E1S_CB_0
  GND_B2  = GND
  IN_B3  = P12V_AUX
  OUT_B4  = P12V_E1S_0
  IN_B5  = P12V_AUX
  OUT_B6  = P12V_E1S_0
  \en#\  = GND
  GND_C1  = GND
  GND_C2  = GND
  IN_C3  = P12V_AUX
  OUT_C4  = P12V_E1S_0
  IN_C5  = P12V_AUX
  OUT_C6  = P12V_E1S_0
  \fault#\  = P12V_E1S_FAULT_0
  REG  = P12V_E1S_REG_0
  UV  = P12V_E1S_UV_0
  OV  = P12V_E1S_OV_0
  OUT_D4  = P12V_E1S_0
  IN_D5  = P12V_AUX
  OUT_D6  = P12V_E1S_0
  PG  = P12V_E1S_PWRGD_0

(kicad_pcb
	(version 20260206)
	(generator "pcbnew")
	(generator_version "10.0")
	(general
		(thickness 1.6)
		(legacy_teardrops no)
	)
	(paper "A4")
	(title_block
		(title "03242023_DA0F0TMBIJ0_F0T_Motherboard_J_brd_V01_OCP.brd")
		(comment 1 "Grand Teton / footprints 3162-3162 of 6105")
	)
	(layers
		(0 "F.Cu" signal "TOP")
		(4 "In1.Cu" signal "GND")
		(6 "In2.Cu" signal "IN1")
		(8 "In3.Cu" signal "GND1")
		(10 "In4.Cu" signal "IN2")
		(12 "In5.Cu" signal "GND2")
		(14 "In6.Cu" signal "IN3")
		(16 "In7.Cu" signal "GND3")
		(18 "In8.Cu" signal "VCC")
		(20 "In9.Cu" signal "VCC1")
		(22 "In10.Cu" signal "GND4")
		(24 "In11.Cu" signal "IN4")
		(26 "In12.Cu" signal "GND5")
		(28 "In13.Cu" signal "IN5")
		(30 "In14.Cu" signal "GND6")
		(32 "In15.Cu" signal "IN6")
		(34 "In16.Cu" signal "GND7")
		(2 "B.Cu" signal "BOTTOM")
		(9 "F.Adhes" user "F.Adhesive")
		(11 "B.Adhes" user "B.Adhesive")
		(13 "F.Paste" user "Package Geometry/Pastemask Top")
		(15 "B.Paste" user "Package Geometry/Pastemask Bottom")
		(5 "F.SilkS" user "Ref Des/Silkscreen Top")
		(7 "B.SilkS" user "Ref Des/Silkscreen Bottom")
		(1 "F.Mask" user "Board Geometry/Soldermask Top")
		(3 "B.Mask" user "Board Geometry/Soldermask Bottom")
		(17 "Dwgs.User" user "User.Drawings")
		(19 "Cmts.User" user "User.Comments")
		(21 "Eco1.User" user "User.Eco1")
		(23 "Eco2.User" user "User.Eco2")
		(25 "Edge.Cuts" user "Board Geometry/Outline")
		(27 "Margin" user)
		(31 "F.CrtYd" user "Package Geometry/Place Bound Top")
		(29 "B.CrtYd" user "Package Geometry/Place Bound Bottom")
		(35 "F.Fab" user "Ref Des/Assembly Top")
		(33 "B.Fab" user "Ref Des/Assembly Bottom")
	)
	(footprint ""
		(layer "F.Cu")
		(at 252.83287 -41.039542 -90)
		(property "Reference" "PU294"
			(at -0.130556 -1.349502 0)
			(unlocked yes)
			(layer "F.SilkS")
			(effects
				(font
					(size 0.7874 0.5842)
					(thickness 0.1524)
				)
				(justify left)
			)
		)
		(property "Value" ""
			(at 0 0 270)
			(layer "F.Fab")
			(effects
				(font
					(size 1.27 1.27)
				)
			)
		)
		(duplicate_pad_numbers_are_jumpers no)
		(fp_line
			(start -1.774952 1.039876)
			(end 1.774952 1.039876)
			(stroke
				(width 0.1524)
				(type default)
			)
			(layer "F.SilkS")
		)
		(fp_line
			(start 1.774952 1.039876)
			(end 1.774952 -1.039876)
			(stroke
				(width 0.1524)
				(type default)
			)
			(layer "F.SilkS")
		)
		(fp_line
			(start -1.774952 -1.039876)
			(end -1.774952 1.039876)
			(stroke
				(width 0.1524)
				(type default)
			)
			(layer "F.SilkS")
		)
		(fp_line
			(start 1.774952 -1.039876)
			(end -1.774952 -1.039876)
			(stroke
				(width 0.1524)
				(type default)
			)
			(layer "F.SilkS")
		)
		(fp_poly
			(pts
				(xy -1.769872 -1.039876) (xy -1.769872 -0.249936) (xy -2.531872 -0.249936) (xy -2.531872 -1.801876)
				(xy -0.999998 -1.801876) (xy -0.999998 -1.039876)
			)
			(stroke
				(width 0)
				(type default)
			)
			(fill yes)
			(layer "F.SilkS")
		)
		(fp_line
			(start -1.769872 1.039876)
			(end 1.769872 1.039876)
			(stroke
				(width 0.1)
				(type default)
			)
			(layer "F.Fab")
		)
		(fp_line
			(start 1.769872 1.039876)
			(end 1.769872 -1.039876)
			(stroke
				(width 0.1)
				(type default)
			)
			(layer "F.Fab")
		)
		(fp_line
			(start -1.769872 -1.039876)
			(end -1.769872 1.039876)
			(stroke
				(width 0.1)
				(type default)
			)
			(layer "F.Fab")
		)
		(fp_line
			(start 1.769872 -1.039876)
			(end -1.769872 -1.039876)
			(stroke
				(width 0.1)
				(type default)
			)
			(layer "F.Fab")
		)
		(fp_poly
			(pts
				(xy -1.769872 -1.039876) (xy -0.999998 -1.039876) (xy -0.999998 -1.801876) (xy -2.531872 -1.801876)
				(xy -2.531872 -0.249936) (xy -1.769872 -0.249936)
			)
			(stroke
				(width 0)
				(type default)
			)
			(fill yes)
			(layer "F.Fab")
		)
		(pad "A1" smd circle
			(at -1.500124 -0.750062 270)
			(size 0.2286 0.2286)
			(layers "F.Cu" "F.Mask" "F.Paste")
			(net "P12V_E1S_SENSE_0")
		)
		(pad "A2" smd circle
			(at -0.999998 -0.750062 270)
			(size 0.2286 0.2286)
			(layers "F.Cu" "F.Mask" "F.Paste")
			(net "P12V_E1S_VCC_0")
		)
		(pad "A3" smd circle
			(at -0.499872 -0.750062 270)
			(size 0.2286 0.2286)
			(layers "F.Cu" "F.Mask" "F.Paste")
			(net "P12V_AUX")
		)
		(pad "A4" smd circle
			(at 0 -0.750062 270)
			(size 0.2286 0.2286)
			(layers "F.Cu" "F.Mask" "F.Paste")
			(net "P12V_E1S_0")
		)
		(pad "A5" smd circle
			(at 0.499872 -0.750062 270)
			(size 0.2286 0.2286)
			(layers "F.Cu" "F.Mask" "F.Paste")
			(net "P12V_AUX")
		)
		(pad "A6" smd circle
			(at 0.999998 -0.750062 270)
			(size 0.2286 0.2286)
			(layers "F.Cu" "F.Mask" "F.Paste")
			(net "P12V_E1S_GATE_0")
		)
		(pad "A7" smd circle
			(at 1.500124 -0.750062 270)
			(size 0.2286 0.2286)
			(layers "F.Cu" "F.Mask" "F.Paste")
			(net "GND")
		)
		(pad "B1" smd circle
			(at -1.500124 -0.249936 270)
			(size 0.2286 0.2286)
			(layers "F.Cu" "F.Mask" "F.Paste")
			(net "P12V_E1S_CB_0")
		)
		(pad "B2" smd circle
			(at -0.999998 -0.249936 270)
			(size 0.2286 0.2286)
			(layers "F.Cu" "F.Mask" "F.Paste")
			(net "GND")
		)
		(pad "B3" smd circle
			(at -0.499872 -0.249936 270)
			(size 0.2286 0.2286)
			(layers "F.Cu" "F.Mask" "F.Paste")
			(net "P12V_AUX")
		)
		(pad "B4" smd circle
			(at 0 -0.249936 270)
			(size 0.2286 0.2286)
			(layers "F.Cu" "F.Mask" "F.Paste")
			(net "P12V_E1S_0")
		)
		(pad "B5" smd circle
			(at 0.499872 -0.249936 270)
			(size 0.2286 0.2286)
			(layers "F.Cu" "F.Mask" "F.Paste")
			(net "P12V_AUX")
		)
		(pad "B6" smd circle
			(at 0.999998 -0.249936 270)
			(size 0.2286 0.2286)
			(layers "F.Cu" "F.Mask" "F.Paste")
			(net "P12V_E1S_0")
		)
		(pad "B7" smd circle
			(at 1.500124 -0.249936 270)
			(size 0.2286 0.2286)
			(layers "F.Cu" "F.Mask" "F.Paste")
			(net "GND")
		)
		(pad "C1" smd circle
			(at -1.500124 0.249936 270)
			(size 0.2286 0.2286)
			(layers "F.Cu" "F.Mask" "F.Paste")
			(net "GND")
		)
		(pad "C2" smd circle
			(at -0.999998 0.249936 270)
			(size 0.2286 0.2286)
			(layers "F.Cu" "F.Mask" "F.Paste")
			(net "GND")
		)
		(pad "C3" smd circle
			(at -0.499872 0.249936 270)
			(size 0.2286 0.2286)
			(layers "F.Cu" "F.Mask" "F.Paste")
			(net "P12V_AUX")
		)
		(pad "C4" smd circle
			(at 0 0.249936 270)
			(size 0.2286 0.2286)
			(layers "F.Cu" "F.Mask" "F.Paste")
			(net "P12V_E1S_0")
		)
		(pad "C5" smd circle
			(at 0.499872 0.249936 270)
			(size 0.2286 0.2286)
			(layers "F.Cu" "F.Mask" "F.Paste")
			(net "P12V_AUX")
		)
		(pad "C6" smd circle
			(at 0.999998 0.249936 270)
			(size 0.2286 0.2286)
			(layers "F.Cu" "F.Mask" "F.Paste")
			(net "P12V_E1S_0")
		)
		(pad "C7" smd circle
			(at 1.500124 0.249936 270)
			(size 0.2286 0.2286)
			(layers "F.Cu" "F.Mask" "F.Paste")
			(net "P12V_E1S_FAULT_0")
		)
		(pad "D1" smd circle
			(at -1.500124 0.750062 270)
			(size 0.2286 0.2286)
			(layers "F.Cu" "F.Mask" "F.Paste")
			(net "P12V_E1S_REG_0")
		)
		(pad "D2" smd circle
			(at -0.999998 0.750062 270)
			(size 0.2286 0.2286)
			(layers "F.Cu" "F.Mask" "F.Paste")
			(net "P12V_E1S_UV_0")
		)
		(pad "D3" smd circle
			(at -0.499872 0.750062 270)
			(size 0.2286 0.2286)
			(layers "F.Cu" "F.Mask" "F.Paste")
			(net "P12V_E1S_OV_0")
		)
		(pad "D4" smd circle
			(at 0 0.750062 270)
			(size 0.2286 0.2286)
			(layers "F.Cu" "F.Mask" "F.Paste")
			(net "P12V_E1S_0")
		)
		(pad "D5" smd circle
			(at 0.499872 0.750062 270)
			(size 0.2286 0.2286)
			(layers "F.Cu" "F.Mask" "F.Paste")
			(net "P12V_AUX")
		)
		(pad "D6" smd circle
			(at 0.999998 0.750062 270)
			(size 0.2286 0.2286)
			(layers "F.Cu" "F.Mask" "F.Paste")
			(net "P12V_E1S_0")
		)
		(pad "D7" smd circle
			(at 1.500124 0.750062 270)
			(size 0.2286 0.2286)
			(layers "F.Cu" "F.Mask" "F.Paste")
			(net "P12V_E1S_PWRGD_0")
		)
	)
)
